(kicad_pcb
	(version 20260206)
	(generator "pcbnew")
	(generator_version "10.0")
	(general
		(thickness 1.6)
		(legacy_teardrops no)
	)
	(paper "A4")
	(title_block
		(title "12092022_DA0F0TMDCD0_F0T_Management_Board_D_brd_V3_OCP.brd")
		(comment 1 "Grand Teton / footprints 1380-1385 of 1440")
	)
	(layers
		(0 "F.Cu" signal "TOP")
		(4 "In1.Cu" signal "GND")
		(6 "In2.Cu" signal "IN1")
		(8 "In3.Cu" signal "GND1")
		(10 "In4.Cu" signal "IN2")
		(12 "In5.Cu" signal "VCC")
		(14 "In6.Cu" signal "VCC1")
		(16 "In7.Cu" signal "IN3")
		(18 "In8.Cu" signal "GND2")
		(20 "In9.Cu" signal "IN4")
		(22 "In10.Cu" signal "GND3")
		(2 "B.Cu" signal "BOTTOM")
		(9 "F.Adhes" user "F.Adhesive")
		(11 "B.Adhes" user "B.Adhesive")
		(13 "F.Paste" user "Package Geometry/Pastemask Top")
		(15 "B.Paste" user "Package Geometry/Pastemask Bottom")
		(5 "F.SilkS" user "Ref Des/Silkscreen Top")
		(7 "B.SilkS" user "Ref Des/Silkscreen Bottom")
		(1 "F.Mask" user "Board Geometry/Soldermask Top")
		(3 "B.Mask" user "Board Geometry/Soldermask Bottom")
		(17 "Dwgs.User" user "User.Drawings")
		(19 "Cmts.User" user "User.Comments")
		(21 "Eco1.User" user "User.Eco1")
		(23 "Eco2.User" user "User.Eco2")
		(25 "Edge.Cuts" user "Board Geometry/Outline")
		(27 "Margin" user)
		(31 "F.CrtYd" user "Package Geometry/Place Bound Top")
		(29 "B.CrtYd" user "Package Geometry/Place Bound Bottom")
		(35 "F.Fab" user "Ref Des/Assembly Top")
		(33 "B.Fab" user "Ref Des/Assembly Bottom")
	)
	(footprint ""
		(layer "B.Cu")
		(at 78.355444 -97.119186 90)
		(property "Reference" "Q10"
			(at -1.273556 3.877056 0)
			(unlocked yes)
			(layer "B.SilkS")
			(effects
				(font
					(size 0.7874 0.5842)
					(thickness 0.1524)
				)
				(justify left mirror)
			)
		)
		(property "Value" ""
			(at 0 0 90)
			(layer "B.Fab")
			(effects
				(font
					(size 1.27 1.27)
				)
				(justify mirror)
			)
		)
		(duplicate_pad_numbers_are_jumpers no)
		(fp_line
			(start 1.603248 -1.500124)
			(end -1.603248 -1.500124)
			(stroke
				(width 0.1524)
				(type default)
			)
			(layer "B.SilkS")
		)
		(fp_line
			(start -1.603248 -1.500124)
			(end -1.603248 1.500124)
			(stroke
				(width 0.1524)
				(type default)
			)
			(layer "B.SilkS")
		)
		(fp_line
			(start 1.603248 1.500124)
			(end 1.603248 -1.500124)
			(stroke
				(width 0.1524)
				(type default)
			)
			(layer "B.SilkS")
		)
		(fp_line
			(start -1.603248 1.500124)
			(end 1.603248 1.500124)
			(stroke
				(width 0.1524)
				(type default)
			)
			(layer "B.SilkS")
		)
		(fp_line
			(start 0.700024 -1.500124)
			(end 0.700024 -1.169924)
			(stroke
				(width 0.1)
				(type default)
			)
			(layer "B.Fab")
		)
		(fp_line
			(start -0.700024 -1.500124)
			(end 0.700024 -1.500124)
			(stroke
				(width 0.1)
				(type default)
			)
			(layer "B.Fab")
		)
		(fp_line
			(start 1.249934 -1.169924)
			(end 1.249934 -0.729996)
			(stroke
				(width 0.1)
				(type default)
			)
			(layer "B.Fab")
		)
		(fp_line
			(start 0.700024 -1.169924)
			(end 1.249934 -1.169924)
			(stroke
				(width 0.1)
				(type default)
			)
			(layer "B.Fab")
		)
		(fp_line
			(start 1.249934 -0.729996)
			(end 0.6985 -0.729996)
			(stroke
				(width 0.1)
				(type default)
			)
			(layer "B.Fab")
		)
		(fp_line
			(start 0.6985 -0.729996)
			(end 0.6985 0.729996)
			(stroke
				(width 0.1)
				(type default)
			)
			(layer "B.Fab")
		)
		(fp_line
			(start -0.700024 -0.219964)
			(end -0.700024 -1.500124)
			(stroke
				(width 0.1)
				(type default)
			)
			(layer "B.Fab")
		)
		(fp_line
			(start -1.249934 -0.219964)
			(end -0.700024 -0.219964)
			(stroke
				(width 0.1)
				(type default)
			)
			(layer "B.Fab")
		)
		(fp_line
			(start -0.700024 0.219964)
			(end -1.249934 0.219964)
			(stroke
				(width 0.1)
				(type default)
			)
			(layer "B.Fab")
		)
		(fp_line
			(start -1.249934 0.219964)
			(end -1.249934 -0.219964)
			(stroke
				(width 0.1)
				(type default)
			)
			(layer "B.Fab")
		)
		(fp_line
			(start 1.249934 0.729996)
			(end 1.249934 1.169924)
			(stroke
				(width 0.1)
				(type default)
			)
			(layer "B.Fab")
		)
		(fp_line
			(start 0.6985 0.729996)
			(end 1.249934 0.729996)
			(stroke
				(width 0.1)
				(type default)
			)
			(layer "B.Fab")
		)
		(fp_line
			(start 1.249934 1.169924)
			(end 0.700024 1.169924)
			(stroke
				(width 0.1)
				(type default)
			)
			(layer "B.Fab")
		)
		(fp_line
			(start 0.700024 1.169924)
			(end 0.700024 1.500124)
			(stroke
				(width 0.1)
				(type default)
			)
			(layer "B.Fab")
		)
		(fp_line
			(start 0.700024 1.500124)
			(end -0.700024 1.500124)
			(stroke
				(width 0.1)
				(type default)
			)
			(layer "B.Fab")
		)
		(fp_line
			(start -0.700024 1.500124)
			(end -0.700024 0.219964)
			(stroke
				(width 0.1)
				(type default)
			)
			(layer "B.Fab")
		)
		(fp_rect
			(start 0.700024 1.500124)
			(end -0.700024 -1.500124)
			(stroke
				(width 0)
				(type default)
			)
			(fill no)
			(layer "B.Fab")
		)
		(pad "D" smd rect
			(at -0.999998 0)
			(size 0.8128 0.9144)
			(layers "B.Cu" "B.Mask" "B.Paste")
			(net "LPC_ESPI_SEL_N")
		)
		(pad "G" smd rect
			(at 0.999998 -0.94996)
			(size 0.8128 0.9144)
			(layers "B.Cu" "B.Mask" "B.Paste")
			(net "LPC_ESPI_SEL_R")
		)
		(pad "S" smd rect
			(at 0.999998 0.94996)
			(size 0.8128 0.9144)
			(layers "B.Cu" "B.Mask" "B.Paste")
			(net "GND")
		)
	)
	(footprint ""
		(layer "B.Cu")
		(at 46.470316 -34.637726 90)
		(property "Reference" "R222"
			(at 0 0 90)
			(layer "B.SilkS")
			(hide yes)
			(effects
				(font
					(size 1.27 1.27)
				)
				(justify mirror)
			)
		)
		(property "Value" ""
			(at 0 0 90)
			(layer "B.Fab")
			(effects
				(font
					(size 1.27 1.27)
				)
				(justify mirror)
			)
		)
		(duplicate_pad_numbers_are_jumpers no)
		(fp_line
			(start 0.7874 -0.4064)
			(end -0.7874 -0.4064)
			(stroke
				(width 0.1524)
				(type default)
			)
			(layer "B.SilkS")
		)
		(fp_line
			(start -0.7874 -0.4064)
			(end -0.7874 0.4064)
			(stroke
				(width 0.1524)
				(type default)
			)
			(layer "B.SilkS")
		)
		(fp_line
			(start 0.7874 0.4064)
			(end 0.7874 -0.4064)
			(stroke
				(width 0.1524)
				(type default)
			)
			(layer "B.SilkS")
		)
		(fp_line
			(start -0.7874 0.4064)
			(end 0.7874 0.4064)
			(stroke
				(width 0.1524)
				(type default)
			)
			(layer "B.SilkS")
		)
		(fp_line
			(start 0.67945 -0.305054)
			(end 0.12065 -0.305054)
			(stroke
				(width 0.1)
				(type default)
			)
			(layer "B.Fab")
		)
		(fp_line
			(start 0.12065 -0.305054)
			(end 0.12065 -0.2794)
			(stroke
				(width 0.1)
				(type default)
			)
			(layer "B.Fab")
		)
		(fp_line
			(start -0.12065 -0.3048)
			(end -0.67945 -0.3048)
			(stroke
				(width 0.1)
				(type default)
			)
			(layer "B.Fab")
		)
		(fp_line
			(start -0.67945 -0.3048)
			(end -0.67945 0.3048)
			(stroke
				(width 0.1)
				(type default)
			)
			(layer "B.Fab")
		)
		(fp_line
			(start 0.12065 -0.2794)
			(end -0.12065 -0.2794)
			(stroke
				(width 0.1)
				(type default)
			)
			(layer "B.Fab")
		)
		(fp_line
			(start -0.12065 -0.2794)
			(end -0.12065 -0.3048)
			(stroke
				(width 0.1)
				(type default)
			)
			(layer "B.Fab")
		)
		(fp_line
			(start 0.12065 0.2794)
			(end 0.12065 0.3048)
			(stroke
				(width 0.1)
				(type default)
			)
			(layer "B.Fab")
		)
		(fp_line
			(start -0.120396 0.2794)
			(end 0.12065 0.2794)
			(stroke
				(width 0.1)
				(type default)
			)
			(layer "B.Fab")
		)
		(fp_line
			(start 0.67945 0.3048)
			(end 0.67945 -0.305054)
			(stroke
				(width 0.1)
				(type default)
			)
			(layer "B.Fab")
		)
		(fp_line
			(start 0.12065 0.3048)
			(end 0.67945 0.3048)
			(stroke
				(width 0.1)
				(type default)
			)
			(layer "B.Fab")
		)
		(fp_line
			(start -0.120396 0.3048)
			(end -0.120396 0.2794)
			(stroke
				(width 0.1)
				(type default)
			)
			(layer "B.Fab")
		)
		(fp_line
			(start -0.67945 0.3048)
			(end -0.120396 0.3048)
			(stroke
				(width 0.1)
				(type default)
			)
			(layer "B.Fab")
		)
		(pad "1" smd circle
			(at 0.40005 0 270)
			(size 0 0)
			(layers "B.Cu" "B.Mask" "B.Paste")
			(net "JTAG_1_BMC_TCK_R")
		)
		(pad "2" smd circle
			(at -0.40005 0 270)
			(size 0 0)
			(layers "B.Cu" "B.Mask" "B.Paste")
			(net "JTAG_MB_TCK")
		)
	)
	(footprint ""
		(layer "B.Cu")
		(at 54.16423 -61.0616 -90)
		(property "Reference" "R179"
			(at 0 0 90)
			(layer "B.SilkS")
			(hide yes)
			(effects
				(font
					(size 1.27 1.27)
				)
				(justify mirror)
			)
		)
		(property "Value" ""
			(at 0 0 90)
			(layer "B.Fab")
			(effects
				(font
					(size 1.27 1.27)
				)
				(justify mirror)
			)
		)
		(duplicate_pad_numbers_are_jumpers no)
		(fp_line
			(start -0.7874 0.4064)
			(end 0.7874 0.4064)
			(stroke
				(width 0.1524)
				(type default)
			)
			(layer "B.SilkS")
		)
		(fp_line
			(start 0.7874 0.4064)
			(end 0.7874 -0.4064)
			(stroke
				(width 0.1524)
				(type default)
			)
			(layer "B.SilkS")
		)
		(fp_line
			(start -0.7874 -0.4064)
			(end -0.7874 0.4064)
			(stroke
				(width 0.1524)
				(type default)
			)
			(layer "B.SilkS")
		)
		(fp_line
			(start 0.7874 -0.4064)
			(end -0.7874 -0.4064)
			(stroke
				(width 0.1524)
				(type default)
			)
			(layer "B.SilkS")
		)
		(fp_line
			(start -0.67945 0.3048)
			(end -0.120396 0.3048)
			(stroke
				(width 0.1)
				(type default)
			)
			(layer "B.Fab")
		)
		(fp_line
			(start -0.120396 0.3048)
			(end -0.120396 0.2794)
			(stroke
				(width 0.1)
				(type default)
			)
			(layer "B.Fab")
		)
		(fp_line
			(start 0.12065 0.3048)
			(end 0.67945 0.3048)
			(stroke
				(width 0.1)
				(type default)
			)
			(layer "B.Fab")
		)
		(fp_line
			(start 0.67945 0.3048)
			(end 0.67945 -0.305054)
			(stroke
				(width 0.1)
				(type default)
			)
			(layer "B.Fab")
		)
		(fp_line
			(start -0.120396 0.2794)
			(end 0.12065 0.2794)
			(stroke
				(width 0.1)
				(type default)
			)
			(layer "B.Fab")
		)
		(fp_line
			(start 0.12065 0.2794)
			(end 0.12065 0.3048)
			(stroke
				(width 0.1)
				(type default)
			)
			(layer "B.Fab")
		)
		(fp_line
			(start -0.12065 -0.2794)
			(end -0.12065 -0.3048)
			(stroke
				(width 0.1)
				(type default)
			)
			(layer "B.Fab")
		)
		(fp_line
			(start 0.12065 -0.2794)
			(end -0.12065 -0.2794)
			(stroke
				(width 0.1)
				(type default)
			)
			(layer "B.Fab")
		)
		(fp_line
			(start -0.67945 -0.3048)
			(end -0.67945 0.3048)
			(stroke
				(width 0.1)
				(type default)
			)
			(layer "B.Fab")
		)
		(fp_line
			(start -0.12065 -0.3048)
			(end -0.67945 -0.3048)
			(stroke
				(width 0.1)
				(type default)
			)
			(layer "B.Fab")
		)
		(fp_line
			(start 0.12065 -0.305054)
			(end 0.12065 -0.2794)
			(stroke
				(width 0.1)
				(type default)
			)
			(layer "B.Fab")
		)
		(fp_line
			(start 0.67945 -0.305054)
			(end 0.12065 -0.305054)
			(stroke
				(width 0.1)
				(type default)
			)
			(layer "B.Fab")
		)
		(pad "1" smd circle
			(at 0.40005 0 90)
			(size 0 0)
			(layers "B.Cu" "B.Mask" "B.Paste")
			(net "SPI_BMC_MOSI_IO0_R")
		)
		(pad "2" smd circle
			(at -0.40005 0 90)
			(size 0 0)
			(layers "B.Cu" "B.Mask" "B.Paste")
			(net "SPI_BMC_BOOT_MOSI")
		)
	)
	(footprint ""
		(layer "B.Cu")
		(at 58.23331 -66.147442 -90)
		(property "Reference" "R241"
			(at 0 0 90)
			(layer "B.SilkS")
			(hide yes)
			(effects
				(font
					(size 1.27 1.27)
				)
				(justify mirror)
			)
		)
		(property "Value" ""
			(at 0 0 90)
			(layer "B.Fab")
			(effects
				(font
					(size 1.27 1.27)
				)
				(justify mirror)
			)
		)
		(duplicate_pad_numbers_are_jumpers no)
		(fp_line
			(start -0.7874 0.4064)
			(end 0.7874 0.4064)
			(stroke
				(width 0.1524)
				(type default)
			)
			(layer "B.SilkS")
		)
		(fp_line
			(start 0.7874 0.4064)
			(end 0.7874 -0.4064)
			(stroke
				(width 0.1524)
				(type default)
			)
			(layer "B.SilkS")
		)
		(fp_line
			(start -0.7874 -0.4064)
			(end -0.7874 0.4064)
			(stroke
				(width 0.1524)
				(type default)
			)
			(layer "B.SilkS")
		)
		(fp_line
			(start 0.7874 -0.4064)
			(end -0.7874 -0.4064)
			(stroke
				(width 0.1524)
				(type default)
			)
			(layer "B.SilkS")
		)
		(fp_line
			(start -0.67945 0.3048)
			(end -0.120396 0.3048)
			(stroke
				(width 0.1)
				(type default)
			)
			(layer "B.Fab")
		)
		(fp_line
			(start -0.120396 0.3048)
			(end -0.120396 0.2794)
			(stroke
				(width 0.1)
				(type default)
			)
			(layer "B.Fab")
		)
		(fp_line
			(start 0.12065 0.3048)
			(end 0.67945 0.3048)
			(stroke
				(width 0.1)
				(type default)
			)
			(layer "B.Fab")
		)
		(fp_line
			(start 0.67945 0.3048)
			(end 0.67945 -0.305054)
			(stroke
				(width 0.1)
				(type default)
			)
			(layer "B.Fab")
		)
		(fp_line
			(start -0.120396 0.2794)
			(end 0.12065 0.2794)
			(stroke
				(width 0.1)
				(type default)
			)
			(layer "B.Fab")
		)
		(fp_line
			(start 0.12065 0.2794)
			(end 0.12065 0.3048)
			(stroke
				(width 0.1)
				(type default)
			)
			(layer "B.Fab")
		)
		(fp_line
			(start -0.12065 -0.2794)
			(end -0.12065 -0.3048)
			(stroke
				(width 0.1)
				(type default)
			)
			(layer "B.Fab")
		)
		(fp_line
			(start 0.12065 -0.2794)
			(end -0.12065 -0.2794)
			(stroke
				(width 0.1)
				(type default)
			)
			(layer "B.Fab")
		)
		(fp_line
			(start -0.67945 -0.3048)
			(end -0.67945 0.3048)
			(stroke
				(width 0.1)
				(type default)
			)
			(layer "B.Fab")
		)
		(fp_line
			(start -0.12065 -0.3048)
			(end -0.67945 -0.3048)
			(stroke
				(width 0.1)
				(type default)
			)
			(layer "B.Fab")
		)
		(fp_line
			(start 0.12065 -0.305054)
			(end 0.12065 -0.2794)
			(stroke
				(width 0.1)
				(type default)
			)
			(layer "B.Fab")
		)
		(fp_line
			(start 0.67945 -0.305054)
			(end 0.12065 -0.305054)
			(stroke
				(width 0.1)
				(type default)
			)
			(layer "B.Fab")
		)
		(pad "1" smd circle
			(at 0.40005 0 90)
			(size 0 0)
			(layers "B.Cu" "B.Mask" "B.Paste")
			(net "P3V3_AUX")
		)
		(pad "2" smd circle
			(at -0.40005 0 90)
			(size 0 0)
			(layers "B.Cu" "B.Mask" "B.Paste")
			(net "PU_SPI1ABR")
		)
	)
	(footprint ""
		(layer "B.Cu")
		(at 64.036194 -28.356306 -90)
		(property "Reference" "R257"
			(at 0 0 90)
			(layer "B.SilkS")
			(hide yes)
			(effects
				(font
					(size 1.27 1.27)
				)
				(justify mirror)
			)
		)
		(property "Value" ""
			(at 0 0 90)
			(layer "B.Fab")
			(effects
				(font
					(size 1.27 1.27)
				)
				(justify mirror)
			)
		)
		(duplicate_pad_numbers_are_jumpers no)
		(fp_line
			(start -0.7874 0.4064)
			(end 0.7874 0.4064)
			(stroke
				(width 0.1524)
				(type default)
			)
			(layer "B.SilkS")
		)
		(fp_line
			(start 0.7874 0.4064)
			(end 0.7874 -0.4064)
			(stroke
				(width 0.1524)
				(type default)
			)
			(layer "B.SilkS")
		)
		(fp_line
			(start -0.7874 -0.4064)
			(end -0.7874 0.4064)
			(stroke
				(width 0.1524)
				(type default)
			)
			(layer "B.SilkS")
		)
		(fp_line
			(start 0.7874 -0.4064)
			(end -0.7874 -0.4064)
			(stroke
				(width 0.1524)
				(type default)
			)
			(layer "B.SilkS")
		)
		(fp_line
			(start -0.67945 0.3048)
			(end -0.120396 0.3048)
			(stroke
				(width 0.1)
				(type default)
			)
			(layer "B.Fab")
		)
		(fp_line
			(start -0.120396 0.3048)
			(end -0.120396 0.2794)
			(stroke
				(width 0.1)
				(type default)
			)
			(layer "B.Fab")
		)
		(fp_line
			(start 0.12065 0.3048)
			(end 0.67945 0.3048)
			(stroke
				(width 0.1)
				(type default)
			)
			(layer "B.Fab")
		)
		(fp_line
			(start 0.67945 0.3048)
			(end 0.67945 -0.305054)
			(stroke
				(width 0.1)
				(type default)
			)
			(layer "B.Fab")
		)
		(fp_line
			(start -0.120396 0.2794)
			(end 0.12065 0.2794)
			(stroke
				(width 0.1)
				(type default)
			)
			(layer "B.Fab")
		)
		(fp_line
			(start 0.12065 0.2794)
			(end 0.12065 0.3048)
			(stroke
				(width 0.1)
				(type default)
			)
			(layer "B.Fab")
		)
		(fp_line
			(start -0.12065 -0.2794)
			(end -0.12065 -0.3048)
			(stroke
				(width 0.1)
				(type default)
			)
			(layer "B.Fab")
		)
		(fp_line
			(start 0.12065 -0.2794)
			(end -0.12065 -0.2794)
			(stroke
				(width 0.1)
				(type default)
			)
			(layer "B.Fab")
		)
		(fp_line
			(start -0.67945 -0.3048)
			(end -0.67945 0.3048)
			(stroke
				(width 0.1)
				(type default)
			)
			(layer "B.Fab")
		)
		(fp_line
			(start -0.12065 -0.3048)
			(end -0.67945 -0.3048)
			(stroke
				(width 0.1)
				(type default)
			)
			(layer "B.Fab")
		)
		(fp_line
			(start 0.12065 -0.305054)
			(end 0.12065 -0.2794)
			(stroke
				(width 0.1)
				(type default)
			)
			(layer "B.Fab")
		)
		(fp_line
			(start 0.67945 -0.305054)
			(end 0.12065 -0.305054)
			(stroke
				(width 0.1)
				(type default)
			)
			(layer "B.Fab")
		)
		(pad "1" smd circle
			(at 0.40005 0 90)
			(size 0 0)
			(layers "B.Cu" "B.Mask" "B.Paste")
			(net "P3V3_AUX")
		)
		(pad "2" smd circle
			(at -0.40005 0 90)
			(size 0 0)
			(layers "B.Cu" "B.Mask" "B.Paste")
			(net "SMB_BMC_MM7_R_SDA")
		)
	)
	(footprint ""
		(layer "B.Cu")
		(at 47.649384 -47.96409 -90)
		(property "Reference" "C31"
			(at 0 0 90)
			(layer "B.SilkS")
			(hide yes)
			(effects
				(font
					(size 1.27 1.27)
				)
				(justify mirror)
			)
		)
		(property "Value" ""
			(at 0 0 90)
			(layer "B.Fab")
			(effects
				(font
					(size 1.27 1.27)
				)
				(justify mirror)
			)
		)
		(duplicate_pad_numbers_are_jumpers no)
		(fp_line
			(start -0.7874 0.4064)
			(end 0.7874 0.4064)
			(stroke
				(width 0.1524)
				(type default)
			)
			(layer "B.SilkS")
		)
		(fp_line
			(start 0.7874 0.4064)
			(end 0.7874 -0.4064)
			(stroke
				(width 0.1524)
				(type default)
			)
			(layer "B.SilkS")
		)
		(fp_line
			(start -0.7874 -0.4064)
			(end -0.7874 0.4064)
			(stroke
				(width 0.1524)
				(type default)
			)
			(layer "B.SilkS")
		)
		(fp_line
			(start 0.7874 -0.4064)
			(end -0.7874 -0.4064)
			(stroke
				(width 0.1524)
				(type default)
			)
			(layer "B.SilkS")
		)
		(fp_line
			(start -0.67945 0.3048)
			(end -0.120396 0.3048)
			(stroke
				(width 0.1)
				(type default)
			)
			(layer "B.Fab")
		)
		(fp_line
			(start -0.120396 0.3048)
			(end -0.120396 0.2794)
			(stroke
				(width 0.1)
				(type default)
			)
			(layer "B.Fab")
		)
		(fp_line
			(start 0.12065 0.3048)
			(end 0.67945 0.3048)
			(stroke
				(width 0.1)
				(type default)
			)
			(layer "B.Fab")
		)
		(fp_line
			(start 0.67945 0.3048)
			(end 0.67945 -0.305054)
			(stroke
				(width 0.1)
				(type default)
			)
			(layer "B.Fab")
		)
		(fp_line
			(start -0.120396 0.2794)
			(end 0.12065 0.2794)
			(stroke
				(width 0.1)
				(type default)
			)
			(layer "B.Fab")
		)
		(fp_line
			(start 0.12065 0.2794)
			(end 0.12065 0.3048)
			(stroke
				(width 0.1)
				(type default)
			)
			(layer "B.Fab")
		)
		(fp_line
			(start -0.12065 -0.2794)
			(end -0.12065 -0.3048)
			(stroke
				(width 0.1)
				(type default)
			)
			(layer "B.Fab")
		)
		(fp_line
			(start 0.12065 -0.2794)
			(end -0.12065 -0.2794)
			(stroke
				(width 0.1)
				(type default)
			)
			(layer "B.Fab")
		)
		(fp_line
			(start -0.67945 -0.3048)
			(end -0.67945 0.3048)
			(stroke
				(width 0.1)
				(type default)
			)
			(layer "B.Fab")
		)
		(fp_line
			(start -0.12065 -0.3048)
			(end -0.67945 -0.3048)
			(stroke
				(width 0.1)
				(type default)
			)
			(layer "B.Fab")
		)
		(fp_line
			(start 0.12065 -0.305054)
			(end 0.12065 -0.2794)
			(stroke
				(width 0.1)
				(type default)
			)
			(layer "B.Fab")
		)
		(fp_line
			(start 0.67945 -0.305054)
			(end 0.12065 -0.305054)
			(stroke
				(width 0.1)
				(type default)
			)
			(layer "B.Fab")
		)
		(pad "1" smd circle
			(at 0.40005 0 90)
			(size 0 0)
			(layers "B.Cu" "B.Mask" "B.Paste")
			(net "P3V3_P2V5_P1V8_RVDD")
		)
		(pad "2" smd circle
			(at -0.40005 0 90)
			(size 0 0)
			(layers "B.Cu" "B.Mask" "B.Paste")
			(net "GND")
		)
	)
)
